(kicad_pcb
	(version 20260206)
	(generator "pcbnew")
	(generator_version "10.0")
	(general
		(thickness 1.6)
		(legacy_teardrops no)
	)
	(paper "A4")
	(title_block
		(title "Bryce Canyon_F.DPB_16315-1-OCP.brd")
		(comment 1 "Bryce Canyon / footprints 402-402 of 2223")
	)
	(layers
		(0 "F.Cu" signal "TOP")
		(4 "In1.Cu" signal "L2GND")
		(6 "In2.Cu" signal "L3")
		(8 "In3.Cu" signal "L4GND")
		(10 "In4.Cu" signal "L5")
		(12 "In5.Cu" signal "L6VCC")
		(14 "In6.Cu" signal "L7VCC")
		(16 "In7.Cu" signal "L8")
		(18 "In8.Cu" signal "L9GND")
		(20 "In9.Cu" signal "L10")
		(22 "In10.Cu" signal "L11GND")
		(2 "B.Cu" signal "BOTTOM")
		(9 "F.Adhes" user "F.Adhesive")
		(11 "B.Adhes" user "B.Adhesive")
		(13 "F.Paste" user "Package Geometry/Pastemask Top")
		(15 "B.Paste" user "Package Geometry/Pastemask Bottom")
		(5 "F.SilkS" user "Ref Des/Silkscreen Top")
		(7 "B.SilkS" user "Ref Des/Silkscreen Bottom")
		(1 "F.Mask" user "Board Geometry/Soldermask Top")
		(3 "B.Mask" user "Board Geometry/Soldermask Bottom")
		(17 "Dwgs.User" user "User.Drawings")
		(19 "Cmts.User" user "User.Comments")
		(21 "Eco1.User" user "User.Eco1")
		(23 "Eco2.User" user "User.Eco2")
		(25 "Edge.Cuts" user "Board Geometry/Outline")
		(27 "Margin" user)
		(31 "F.CrtYd" user "Package Geometry/Place Bound Top")
		(29 "B.CrtYd" user "Package Geometry/Place Bound Bottom")
		(35 "F.Fab" user "Ref Des/Assembly Top")
		(33 "B.Fab" user "Ref Des/Assembly Bottom")
	)
	(footprint ""
		(layer "F.Cu")
		(at 59.749944 -172.909992 -90)
		(property "Reference" "HDDSAS13"
			(at 0 0 270)
			(layer "F.SilkS")
			(hide yes)
			(effects
				(font
					(size 1.27 1.27)
				)
			)
		)
		(property "Value" "SKT-SAS15P-14P-45-GP"
			(at -20.7645 -8.9789 270)
			(unlocked yes)
			(layer "F.Fab")
			(hide yes)
			(effects
				(font
					(size 1.016 1.016)
					(thickness 0.1524)
				)
			)
		)
		(property "Device Type" "10120818-001C-TRLF"
			(at -20.7645 -10.5029 270)
			(unlocked yes)
			(layer "F.Fab")
			(hide yes)
			(effects
				(font
					(size 1.016 1.016)
					(thickness 0.1524)
				)
			)
		)
		(duplicate_pad_numbers_are_jumpers no)
		(fp_line
			(start 1.651 4.2926)
			(end 1.651 3.0099)
			(stroke
				(width 0.1524)
				(type default)
			)
			(layer "F.SilkS")
		)
		(fp_line
			(start 8.509 4.2926)
			(end 1.651 4.2926)
			(stroke
				(width 0.1524)
				(type default)
			)
			(layer "F.SilkS")
		)
		(fp_line
			(start -23.4188 3.0099)
			(end -23.4188 -3.2512)
			(stroke
				(width 0.1524)
				(type default)
			)
			(layer "F.SilkS")
		)
		(fp_line
			(start 1.651 3.0099)
			(end -23.4188 3.0099)
			(stroke
				(width 0.1524)
				(type default)
			)
			(layer "F.SilkS")
		)
		(fp_line
			(start 8.509 3.0099)
			(end 8.509 4.2926)
			(stroke
				(width 0.1524)
				(type default)
			)
			(layer "F.SilkS")
		)
		(fp_line
			(start 23.4188 3.0099)
			(end 8.509 3.0099)
			(stroke
				(width 0.1524)
				(type default)
			)
			(layer "F.SilkS")
		)
		(fp_line
			(start -23.4188 -3.2512)
			(end 23.4188 -3.2512)
			(stroke
				(width 0.1524)
				(type default)
			)
			(layer "F.SilkS")
		)
		(fp_line
			(start 23.4188 -3.2512)
			(end 23.4188 3.0099)
			(stroke
				(width 0.1524)
				(type default)
			)
			(layer "F.SilkS")
		)
		(fp_line
			(start 15.5067 -3.3401)
			(end 16.2687 -3.3401)
			(stroke
				(width 0.3302)
				(type default)
			)
			(layer "F.SilkS")
		)
		(fp_poly
			(pts
				(xy 15.868904 -3.230372) (xy 16.503904 -3.865372) (xy 15.233904 -3.865372)
			)
			(stroke
				(width 0)
				(type default)
			)
			(fill yes)
			(layer "F.SilkS")
		)
		(fp_poly
			(pts
				(xy -22.8727 -2.7559) (xy 22.8727 -2.7559) (xy 22.8727 2.7559) (xy 8.255 2.7559) (xy 8.255 3.5179)
				(xy 1.905 3.5179) (xy 1.905 2.7559) (xy -22.8727 2.7559)
			)
			(stroke
				(width 0)
				(type default)
			)
			(fill no)
			(layer "F.CrtYd")
		)
		(fp_poly
			(pts
				(xy 1.397 4.5466) (xy 1.397 3.2639) (xy -23.6728 3.2639) (xy -23.6728 -3.5052) (xy 23.6728 -3.5052)
				(xy 23.6728 -0.00635) (xy 22.8727 -0.00635) (xy 22.8727 -2.7559) (xy -22.8727 -2.7559) (xy -22.8727 2.7559)
				(xy 1.905 2.7559) (xy 1.905 3.5179) (xy 8.255 3.5179) (xy 8.255 2.7559) (xy 22.8727 2.7559) (xy 22.8727 0.00635)
				(xy 23.6728 0.00635) (xy 23.6728 3.2639) (xy 8.763 3.2639) (xy 8.763 4.5466)
			)
			(stroke
				(width 0)
				(type default)
			)
			(fill no)
			(layer "F.CrtYd")
		)
		(fp_poly
			(pts
				(xy 1.397 4.5466) (xy 1.397 3.2639) (xy -23.6728 3.2639) (xy -23.6728 -3.5052) (xy 23.6728 -3.5052)
				(xy 23.6728 3.2639) (xy 8.763 3.2639) (xy 8.763 4.5466)
			)
			(stroke
				(width 0)
				(type default)
			)
			(fill no)
			(layer "F.Fab")
		)
		(pad "" np_thru_hole circle
			(at -18.874994 0 270)
			(size 0.254 0.254)
			(drill 1.3462)
			(layers "*.Cu" "*.Mask")
			(clearance 0.9017)
			(thermal_gap 0.9017)
		)
		(pad "" np_thru_hole circle
			(at 18.874994 0 270)
			(size 0.254 0.254)
			(drill 0.9398)
			(layers "*.Cu" "*.Mask")
			(clearance 0.6985)
			(thermal_gap 0.6985)
		)
		(pad "G1" smd rect
			(at 21.874988 0 270)
			(size 2.5908 2.5908)
			(layers "F.Cu" "F.Mask" "F.Paste")
			(net "GND")
		)
		(pad "G2" smd rect
			(at -21.874988 0 270)
			(size 2.5908 2.5908)
			(layers "F.Cu" "F.Mask" "F.Paste")
			(net "GND")
		)
		(pad "P1" smd rect
			(at 1.905 -1.82499 270)
			(size 0.6096 2.3622)
			(layers "F.Cu" "F.Mask" "F.Paste")
			(net "Net_2151")
		)
		(pad "P2" smd rect
			(at 0.635 -1.82499 270)
			(size 0.6096 2.3622)
			(layers "F.Cu" "F.Mask" "F.Paste")
			(net "Net_2152")
		)
		(pad "P3" smd rect
			(at -0.635 -1.82499 270)
			(size 0.6096 2.3622)
			(layers "F.Cu" "F.Mask" "F.Paste")
			(net "Net_2153")
		)
		(pad "P4" smd rect
			(at -1.905 -1.82499 270)
			(size 0.6096 2.3622)
			(layers "F.Cu" "F.Mask" "F.Paste")
			(net "GND")
		)
		(pad "P5" smd rect
			(at -3.175 -1.82499 270)
			(size 0.6096 2.3622)
			(layers "F.Cu" "F.Mask" "F.Paste")
			(net "HDD_PRSNT_13")
		)
		(pad "P6" smd rect
			(at -4.445 -1.82499 270)
			(size 0.6096 2.3622)
			(layers "F.Cu" "F.Mask" "F.Paste")
			(net "GND")
		)
		(pad "P7" smd rect
			(at -5.715 -1.82499 270)
			(size 0.6096 2.3622)
			(layers "F.Cu" "F.Mask" "F.Paste")
			(net "5V_PRE_13")
		)
		(pad "P8" smd rect
			(at -6.985 -1.82499 270)
			(size 0.6096 2.3622)
			(layers "F.Cu" "F.Mask" "F.Paste")
			(net "P5V_HDD13")
		)
		(pad "P9" smd rect
			(at -8.255 -1.82499 270)
			(size 0.6096 2.3622)
			(layers "F.Cu" "F.Mask" "F.Paste")
			(net "P5V_HDD13")
		)
		(pad "P10" smd rect
			(at -9.525 -1.82499 270)
			(size 0.6096 2.3622)
			(layers "F.Cu" "F.Mask" "F.Paste")
			(net "GND")
		)
		(pad "P11" smd rect
			(at -10.795 -1.82499 270)
			(size 0.6096 2.3622)
			(layers "F.Cu" "F.Mask" "F.Paste")
			(net "ACT_HDD_13")
		)
		(pad "P12" smd rect
			(at -12.065 -1.82499 270)
			(size 0.6096 2.3622)
			(layers "F.Cu" "F.Mask" "F.Paste")
			(net "GND")
		)
		(pad "P13" smd rect
			(at -13.335 -1.82499 270)
			(size 0.6096 2.3622)
			(layers "F.Cu" "F.Mask" "F.Paste")
			(net "12V_PRE_13")
		)
		(pad "P14" smd rect
			(at -14.605 -1.82499 270)
			(size 0.6096 2.3622)
			(layers "F.Cu" "F.Mask" "F.Paste")
			(net "P12V_HDD13")
		)
		(pad "P15" smd rect
			(at -15.875 -1.82499 270)
			(size 0.6096 2.3622)
			(layers "F.Cu" "F.Mask" "F.Paste")
			(net "P12V_HDD13")
		)
		(pad "S1" smd rect
			(at 15.875 -1.82499 270)
			(size 0.6096 2.3622)
			(layers "F.Cu" "F.Mask" "F.Paste")
			(net "GND")
		)
		(pad "S2" smd rect
			(at 14.605 -1.82499 270)
			(size 0.6096 2.3622)
			(layers "F.Cu" "F.Mask" "F.Paste")
			(net "SAS_HDD_RX_P13")
		)
		(pad "S3" smd rect
			(at 13.335 -1.82499 270)
			(size 0.6096 2.3622)
			(layers "F.Cu" "F.Mask" "F.Paste")
			(net "SAS_HDD_RX_N13")
		)
		(pad "S4" smd rect
			(at 12.065 -1.82499 270)
			(size 0.6096 2.3622)
			(layers "F.Cu" "F.Mask" "F.Paste")
			(net "GND")
		)
		(pad "S5" smd rect
			(at 10.795 -1.82499 270)
			(size 0.6096 2.3622)
			(layers "F.Cu" "F.Mask" "F.Paste")
			(net "PHY_DRV_A_TO_SCC_A_13_DN")
		)
		(pad "S6" smd rect
			(at 9.525 -1.82499 270)
			(size 0.6096 2.3622)
			(layers "F.Cu" "F.Mask" "F.Paste")
			(net "PHY_DRV_A_TO_SCC_A_13_DP")
		)
		(pad "S7" smd rect
			(at 8.255 -1.82499 270)
			(size 0.6096 2.3622)
			(layers "F.Cu" "F.Mask" "F.Paste")
			(net "GND")
		)
		(pad "S8" smd rect
			(at 7.480046 2.845054 270)
			(size 0.508 2.3622)
			(layers "F.Cu" "F.Mask" "F.Paste")
			(net "GND")
		)
		(pad "S9" smd rect
			(at 6.679946 2.845054 270)
			(size 0.508 2.3622)
			(layers "F.Cu" "F.Mask" "F.Paste")
			(net "Net_450")
		)
		(pad "S10" smd rect
			(at 5.8801 2.845054 270)
			(size 0.508 2.3622)
			(layers "F.Cu" "F.Mask" "F.Paste")
			(net "Net_342")
		)
		(pad "S11" smd rect
			(at 5.08 2.845054 270)
			(size 0.508 2.3622)
			(layers "F.Cu" "F.Mask" "F.Paste")
			(net "GND")
		)
		(pad "S12" smd rect
			(at 4.2799 2.845054 270)
			(size 0.508 2.3622)
			(layers "F.Cu" "F.Mask" "F.Paste")
			(net "Net_378")
		)
		(pad "S13" smd rect
			(at 3.480054 2.845054 270)
			(size 0.508 2.3622)
			(layers "F.Cu" "F.Mask" "F.Paste")
			(net "Net_414")
		)
		(pad "S14" smd rect
			(at 2.679954 2.845054 270)
			(size 0.508 2.3622)
			(layers "F.Cu" "F.Mask" "F.Paste")
			(net "GND")
		)
		(zone
			(layer "F.Cu")
			(hatch none 0.5)
			(connect_pads
				(clearance 0)
			)
			(min_thickness 0.25)
			(keepout
				(tracks allowed)
				(vias not_allowed)
				(pads allowed)
				(copperpour not_allowed)
				(footprints allowed)
			)
			(placement
				(enabled no)
				(sheetname "")
			)
			(fill
				(thermal_gap 0.5)
				(thermal_bridge_width 0.5)
				(island_removal_mode 0)
			)
			(polygon
				(pts
					(xy 63.407544 -189.648592) (xy 56.333644 -189.648592) (xy 56.333644 -196.582792) (xy 57.438544 -196.582792)
					(xy 57.438544 -192.467992) (xy 62.061344 -192.467992) (xy 62.061344 -196.582792) (xy 63.407544 -196.582792)
				)
			)
		)
		(zone
			(layer "F.Cu")
			(hatch none 0.5)
			(connect_pads
				(clearance 0)
			)
			(min_thickness 0.25)
			(keepout
				(tracks not_allowed)
				(vias allowed)
				(pads allowed)
				(copperpour not_allowed)
				(footprints allowed)
			)
			(placement
				(enabled no)
				(sheetname "")
			)
			(fill
				(thermal_gap 0.5)
				(thermal_bridge_width 0.5)
				(island_removal_mode 0)
			)
			(polygon
				(pts
					(xy 63.407544 -189.648592) (xy 56.333644 -189.648592) (xy 56.333644 -196.582792) (xy 57.438544 -196.582792)
					(xy 57.438544 -192.467992) (xy 62.061344 -192.467992) (xy 62.061344 -196.582792) (xy 63.407544 -196.582792)
				)
			)
		)
		(zone
			(layer "F.Cu")
			(hatch none 0.5)
			(connect_pads
				(clearance 0)
			)
			(min_thickness 0.25)
			(keepout
				(tracks allowed)
				(vias not_allowed)
				(pads allowed)
				(copperpour not_allowed)
				(footprints allowed)
			)
			(placement
				(enabled no)
				(sheetname "")
			)
			(fill
				(thermal_gap 0.5)
				(thermal_bridge_width 0.5)
				(island_removal_mode 0)
			)
			(polygon
				(pts
					(xy 63.407544 -156.171392) (xy 56.333644 -156.171392) (xy 56.333644 -149.237192) (xy 57.438544 -149.237192)
					(xy 57.438544 -153.351992) (xy 62.061344 -153.351992) (xy 62.061344 -149.237192) (xy 63.407544 -149.237192)
				)
			)
		)
		(zone
			(layer "F.Cu")
			(hatch none 0.5)
			(connect_pads
				(clearance 0)
			)
			(min_thickness 0.25)
			(keepout
				(tracks not_allowed)
				(vias allowed)
				(pads allowed)
				(copperpour not_allowed)
				(footprints allowed)
			)
			(placement
				(enabled no)
				(sheetname "")
			)
			(fill
				(thermal_gap 0.5)
				(thermal_bridge_width 0.5)
				(island_removal_mode 0)
			)
			(polygon
				(pts
					(xy 63.407544 -156.171392) (xy 56.333644 -156.171392) (xy 56.333644 -149.237192) (xy 57.438544 -149.237192)
					(xy 57.438544 -153.351992) (xy 62.061344 -153.351992) (xy 62.061344 -149.237192) (xy 63.407544 -149.237192)
				)
			)
		)
		(zone
			(layers "F.Cu" "B.Cu" "In1.Cu" "In2.Cu" "In3.Cu" "In4.Cu" "In5.Cu" "In6.Cu"
				"In7.Cu" "In8.Cu" "In9.Cu" "In10.Cu"
			)
			(hatch none 0.5)
			(connect_pads
				(clearance 0)
			)
			(min_thickness 0.25)
			(keepout
				(tracks not_allowed)
				(vias allowed)
				(pads allowed)
				(copperpour not_allowed)
				(footprints allowed)
			)
			(placement
				(enabled no)
				(sheetname "")
			)
			(fill
				(thermal_gap 0.5)
				(thermal_bridge_width 0.5)
				(island_removal_mode 0)
			)
			(polygon
				(pts
					(arc
						(start 60.524644 -154.034998)
						(mid 58.975244 -154.034998)
						(end 60.524644 -154.034998)
					)
				)
			)
		)
		(zone
			(layers "F.Cu" "B.Cu" "In1.Cu" "In2.Cu" "In3.Cu" "In4.Cu" "In5.Cu" "In6.Cu"
				"In7.Cu" "In8.Cu" "In9.Cu" "In10.Cu"
			)
			(hatch none 0.5)
			(connect_pads
				(clearance 0)
			)
			(min_thickness 0.25)
			(keepout
				(tracks not_allowed)
				(vias allowed)
				(pads allowed)
				(copperpour not_allowed)
				(footprints allowed)
			)
			(placement
				(enabled no)
				(sheetname "")
			)
			(fill
				(thermal_gap 0.5)
				(thermal_bridge_width 0.5)
				(island_removal_mode 0)
			)
			(polygon
				(pts
					(arc
						(start 60.727844 -191.784986)
						(mid 58.772044 -191.784986)
						(end 60.727844 -191.784986)
					)
				)
			)
		)
	)
)
